# S9S_MB_2U (Grand Teton) — schematic netlist excerpt (pin names and nets, part order shuffled) for the footprints in the layout excerpt that follows; sources: Cadence DE-HDL packaged netlist, KiCad conversion of 03242023_DA0F0TMBIJ0_F0T_Motherboard_J_brd_V01_OCP.brd

J24  SCONN288_ADR50017P087CC  SCONN288_ADR50017-P087CC IO  pkg DDR288S_1-1VXB  page 105
  VIN_BULK0  = P12V_S3_AUX_CPU1_NVDIMM
  RFU0  = TP_CHD_CPU1_DIMM2_FRU_0
  VIN_MGMT  = P3V3_AUX
  HSCL  = I3C_SPD_DDRABCD_CPU1_LVC1_SCL_7
  HSDA  = I3C_SPD_DDRABCD_CPU1_LVC1_SDA
  VSS0  = GND
  DQ0_A  = M_D_CPU1_SA_DQ<0>
  VSS1  = GND
  DQ1_A  = M_D_CPU1_SA_DQ<1>
  VSS2  = GND
  DQS0_A_T  = M_D_CPU1_SA_DQS_DP<0>
  DQS0_A_C  = M_D_CPU1_SA_DQS_DN<0>
  VSS3  = GND
  DQ4_A  = M_D_CPU1_SA_DQ<4>
  VSS4  = GND
  DQ5_A  = M_D_CPU1_SA_DQ<5>
  VSS5  = GND
  DQ8_A  = M_D_CPU1_SA_DQ<8>
  VSS6  = GND
  DQ9_A  = M_D_CPU1_SA_DQ<9>
  VSS7  = GND
  DQS1_A_T  = M_D_CPU1_SA_DQS_DP<1>
  DQS1_A_C  = M_D_CPU1_SA_DQS_DN<1>
  VSS8  = GND
  DQ12_A  = M_D_CPU1_SA_DQ<12>
  VSS9  = GND
  DQ13_A  = M_D_CPU1_SA_DQ<13>
  VSS10  = GND
  DQ16_A  = M_D_CPU1_SA_DQ<16>
  VSS11  = GND
  DQ17_A  = M_D_CPU1_SA_DQ<17>
  VSS12  = GND
  DQS2_A_T  = M_D_CPU1_SA_DQS_DP<2>
  DQS2_A_C  = M_D_CPU1_SA_DQS_DN<2>
  VSS13  = GND
  DQ20_A  = M_D_CPU1_SA_DQ<20>
  VSS14  = GND
  DQ21_A  = M_D_CPU1_SA_DQ<21>
  VSS15  = GND
  DQ24_A  = M_D_CPU1_SA_DQ<24>
  VSS16  = GND
  DQ25_A  = M_D_CPU1_SA_DQ<25>
  VSS17  = GND
  DQS3_A_T  = M_D_CPU1_SA_DQS_DP<3>
  DQS3_A_C  = M_D_CPU1_SA_DQS_DN<3>
  VSS18  = GND
  DQ28_A  = M_D_CPU1_SA_DQ<28>
  VSS19  = GND
  DQ29_A  = M_D_CPU1_SA_DQ<29>
  VSS20  = GND
  CB0_A  = M_D_CPU1_SA_CB<0>
  VSS21  = GND
  CB1_A  = M_D_CPU1_SA_CB<1>
  VSS22  = GND
  DQS4_A_T  = M_D_CPU1_SA_DQS_DP<4>
  DQS4_A_C  = M_D_CPU1_SA_DQS_DN<4>
  VSS23  = GND
  CB4_A  = M_D_CPU1_SA_CB<4>
  VSS24  = GND
  CB5_A  = M_D_CPU1_SA_CB<5>
  VSS25  = GND
  ALERT_N  = M_D_CPU1_ALERT_N
  VSS26  = GND
  CS0_A_N  = M_D_CPU1_SA_CS_N<2>
  VSS27  = GND
  CA0_A  = M_D_CPU1_SA_CA<0>
  VSS28  = GND
  CA2_A  = M_D_CPU1_SA_CA<2>
  VSS29  = GND
  CA4_A  = M_D_CPU1_SA_CA<4>
  VSS30  = GND
  CA6_A  = M_D_CPU1_SA_CA<6>
  VSS31  = GND
  PAR_A  = M_D_CPU1_SA_PAR
  VSS32  = GND
  CA0_B  = M_D_CPU1_SB_CA<0>
  VSS33  = GND
  CA2_B  = M_D_CPU1_SB_CA<2>
  VSS34  = GND
  CA4_B  = M_D_CPU1_SB_CA<4>
  VSS35  = GND
  CA6_B  = M_D_CPU1_SB_CA<6>
  VSS36  = GND
  CS0_B_N  = M_D_CPU1_SB_CS_N<2>
  VSS37  = GND
  \lbd||rsp_a_n\  = M_D_CPU1_SA_RSP<1>
  \lbs||rsp_b_n\  = M_D_CPU1_SB_RSP<1>
  VSS38  = GND
  CB4_B  = M_D_CPU1_SB_CB<4>
  VSS39  = GND
  CB5_B  = M_D_CPU1_SB_CB<5>
  VSS40  = GND
  \dqs9_b_t||tdqs9_b_t||dbi4_b_n\  = M_D_CPU1_SB_DQS_DP<9>
  \dqs9_b_c||tdqs9_b_c\  = M_D_CPU1_SB_DQS_DN<9>
  VSS41  = GND
  CB0_B  = M_D_CPU1_SB_CB<0>
  VSS42  = GND
  CB1_B  = M_D_CPU1_SB_CB<1>
  VSS43  = GND
  DQ0_B  = M_D_CPU1_SB_DQ<0>
  VSS44  = GND
  DQ1_B  = M_D_CPU1_SB_DQ<1>
  VSS45  = GND
  DQS0_B_T  = M_D_CPU1_SB_DQS_DP<0>
  DQS0_B_C  = M_D_CPU1_SB_DQS_DN<0>
  VSS46  = GND
  DQ4_B  = M_D_CPU1_SB_DQ<4>
  VSS47  = GND
  DQ5_B  = M_D_CPU1_SB_DQ<5>
  VSS48  = GND
  DQ8_B  = M_D_CPU1_SB_DQ<8>
  VSS49  = GND
  DQ9_B  = M_D_CPU1_SB_DQ<9>
  VSS50  = GND
  DQS1_B_T  = M_D_CPU1_SB_DQS_DP<1>
  DQS1_B_C  = M_D_CPU1_SB_DQS_DN<1>
  VSS51  = GND
  DQ12_B  = M_D_CPU1_SB_DQ<12>
  VSS52  = GND
  DQ13_B  = M_D_CPU1_SB_DQ<13>
  VSS53  = GND
  DQ16_B  = M_D_CPU1_SB_DQ<16>
  VSS54  = GND
  DQ17_B  = M_D_CPU1_SB_DQ<17>
  VSS55  = GND
  DQS2_B_T  = M_D_CPU1_SB_DQS_DP<2>
  DQS2_B_C  = M_D_CPU1_SB_DQS_DN<2>
  VSS56  = GND
  DQ20_B  = M_D_CPU1_SB_DQ<20>
  VSS57  = GND
  DQ21_B  = M_D_CPU1_SB_DQ<21>
  VSS58  = GND
  DQ24_B  = M_D_CPU1_SB_DQ<24>
  VSS59  = GND
  DQ25_B  = M_D_CPU1_SB_DQ<25>
  VSS60  = GND
  DQS3_B_T  = M_D_CPU1_SB_DQS_DP<3>
  DQS3_B_C  = M_D_CPU1_SB_DQS_DN<3>
  VSS61  = GND
  DQ28_B  = M_D_CPU1_SB_DQ<28>
  VSS62  = GND
  DQ29_B  = M_D_CPU1_SB_DQ<29>
  VSS63  = GND
  RFU1  = TP_CHD_CPU1_DIMM2_FRU_1
  VIN_BULK1  = P12V_S3_AUX_CPU1_NVDIMM
  VIN_BULK2  = P12V_S3_AUX_CPU1_NVDIMM
  \pwr_good||fail_n\  = PWRGD_CHD_CPU1_DIMM2
  HSA  = PD_CHD_CPU1_DIMM2_SAA
  RFU2  = TP_CHD_CPU1_DIMM2_FRU_2
  RFU3  = TP_CHD_CPU1_DIMM2_FRU_3
  VSS64  = GND
  DQ2_A  = M_D_CPU1_SA_DQ<2>
  VSS65  = GND
  DQ3_A  = M_D_CPU1_SA_DQ<3>
  VSS66  = GND
  \dqs5_a_c||tdqs5_a_c||dqs5_a_t||tdqs5_a_t\  = M_D_CPU1_SA_DQS_DN<5>
  \dqs5_a_t||tdqs5_a_t\  = M_D_CPU1_SA_DQS_DP<5>
  VSS67  = GND
  DQ6_A  = M_D_CPU1_SA_DQ<6>
  VSS68  = GND
  DQ7_A  = M_D_CPU1_SA_DQ<7>
  VSS69  = GND
  DQ10_A  = M_D_CPU1_SA_DQ<10>
  VSS70  = GND
  DQ11_A  = M_D_CPU1_SA_DQ<11>
  VSS71  = GND
  \dqs6_a_c||tdqs6_a_c||dqs6_a_t||tdqs6_a_t\  = M_D_CPU1_SA_DQS_DN<6>
  \dqs6_a_t||tdqs6_a_t\  = M_D_CPU1_SA_DQS_DP<6>
  VSS72  = GND
  DQ14_A  = M_D_CPU1_SA_DQ<14>
  VSS73  = GND
  DQ15_A  = M_D_CPU1_SA_DQ<15>
  VSS74  = GND
  DQ18_A  = M_D_CPU1_SA_DQ<18>
  VSS75  = GND
  DQ19_A  = M_D_CPU1_SA_DQ<19>
  VSS76  = GND
  \dqs7_a_c||tdqs7_a_c\  = M_D_CPU1_SA_DQS_DN<7>
  \dqs7_a_t||tdqs7_a_t\  = M_D_CPU1_SA_DQS_DP<7>
  VSS77  = GND
  DQ22_A  = M_D_CPU1_SA_DQ<22>
  VSS78  = GND
  DQ23_A  = M_D_CPU1_SA_DQ<23>
  VSS79  = GND
  DQ26_A  = M_D_CPU1_SA_DQ<26>
  VSS80  = GND
  DQ27_A  = M_D_CPU1_SA_DQ<27>
  VSS81  = GND
  \dqs8_a_c||tdqs8_a_c\  = M_D_CPU1_SA_DQS_DN<8>
  \dqs8_a_t||tdqs8_a_t\  = M_D_CPU1_SA_DQS_DP<8>
  VSS82  = GND
  DQ30_A  = M_D_CPU1_SA_DQ<30>
  VSS83  = GND
  DQ31_A  = M_D_CPU1_SA_DQ<31>
  VSS84  = GND
  CB2_A  = M_D_CPU1_SA_CB<2>
  VSS85  = GND
  CB3_A  = M_D_CPU1_SA_CB<3>
  VSS86  = GND
  \dqs9_a_c||tdqs9_a_c\  = M_D_CPU1_SA_DQS_DN<9>
  \dqs9_a_t||tdqs9_a_t\  = M_D_CPU1_SA_DQS_DP<9>
  VSS87  = GND
  CB6_A  = M_D_CPU1_SA_CB<6>
  VSS88  = GND
  CB7_A  = M_D_CPU1_SA_CB<7>
  VSS89  = GND
  RESET_N  = RST_M_CD_CPU1_FPGA_N
  VSS90  = GND
  CS1_A_N  = M_D_CPU1_SA_CS_N<3>
  VSS91  = GND
  CA1_A  = M_D_CPU1_SA_CA<1>
  VSS92  = GND
  CA3_A  = M_D_CPU1_SA_CA<3>
  VSS93  = GND
  CA5_A  = M_D_CPU1_SA_CA<5>
  VSS94  = GND
  CK_T  = M_D_CPU1_CLK_DP<1>
  CK_C  = M_D_CPU1_CLK_DN<1>
  VSS95  = GND
  RFU4  = TP_CHD_CPU1_DIMM2_FRU_4
  CA1_B  = M_D_CPU1_SB_CA<1>
  VSS96  = GND
  CA3_B  = M_D_CPU1_SB_CA<3>
  VSS97  = GND
  CA5_B  = M_D_CPU1_SB_CA<5>
  VSS98  = GND
  PAR_B  = M_D_CPU1_SB_PAR
  VSS99  = GND
  CS1_B_N  = M_D_CPU1_SB_CS_N<3>
  VSS100  = GND
  RFU5  = TP_CHD_CPU1_DIMM2_FRU_5
  RFU6  = TP_CHD_CPU1_DIMM2_FRU_6
  VSS101  = GND
  CB6_B  = M_D_CPU1_SB_CB<6>
  VSS102  = GND
  CB7_B  = M_D_CPU1_SB_CB<7>
  VSS103  = GND
  DQS4_B_C  = M_D_CPU1_SB_DQS_DN<4>
  DQS4_B_T  = M_D_CPU1_SB_DQS_DP<4>
  VSS104  = GND
  CB2_B  = M_D_CPU1_SB_CB<2>
  VSS105  = GND
  CB3_B  = M_D_CPU1_SB_CB<3>
  VSS106  = GND
  DQ2_B  = M_D_CPU1_SB_DQ<2>
  VSS107  = GND
  DQ3_B  = M_D_CPU1_SB_DQ<3>
  VSS108  = GND
  \dqs5_b_c||tdqs5_b_c\  = M_D_CPU1_SB_DQS_DN<5>
  \dqs5_b_t||tdqs5_b_t\  = M_D_CPU1_SB_DQS_DP<5>
  VSS109  = GND
  DQ6_B  = M_D_CPU1_SB_DQ<6>
  VSS110  = GND
  DQ7_B  = M_D_CPU1_SB_DQ<7>
  VSS111  = GND
  DQ10_B  = M_D_CPU1_SB_DQ<10>
  VSS112  = GND
  DQ11_B  = M_D_CPU1_SB_DQ<11>
  VSS113  = GND
  \dqs6_b_c||tdqs6_b_c\  = M_D_CPU1_SB_DQS_DN<6>
  \dqs6_b_t||tdqs6_b_t\  = M_D_CPU1_SB_DQS_DP<6>
  VSS114  = GND
  DQ14_B  = M_D_CPU1_SB_DQ<14>
  VSS115  = GND
  DQ15_B  = M_D_CPU1_SB_DQ<15>
  VSS116  = GND
  DQ18_B  = M_D_CPU1_SB_DQ<18>
  VSS117  = GND
  DQ19_B  = M_D_CPU1_SB_DQ<19>
  VSS118  = GND
  \dqs7_b_c||tdqs7_b_c\  = M_D_CPU1_SB_DQS_DN<7>
  \dqs7_b_t||tdqs7_b_t\  = M_D_CPU1_SB_DQS_DP<7>
  VSS119  = GND
  DQ22_B  = M_D_CPU1_SB_DQ<22>
  VSS120  = GND
  DQ23_B  = M_D_CPU1_SB_DQ<23>
  VSS121  = GND
  DQ26_B  = M_D_CPU1_SB_DQ<26>
  VSS122  = GND
  DQ27_B  = M_D_CPU1_SB_DQ<27>
  VSS123  = GND
  \dqs8_b_c||tdqs8_b_c\  = M_D_CPU1_SB_DQS_DN<8>
  \dqs8_b_t||tdqs8_b_t\  = M_D_CPU1_SB_DQS_DP<8>
  VSS124  = GND
  DQ30_B  = M_D_CPU1_SB_DQ<30>
  VSS125  = GND
  DQ31_B  = M_D_CPU1_SB_DQ<31>
  VSS126  = GND
  G1  = GND
  G2  = GND
  G3  = GND

(kicad_pcb
	(version 20260206)
	(generator "pcbnew")
	(generator_version "10.0")
	(general
		(thickness 1.6)
		(legacy_teardrops no)
	)
	(paper "A4")
	(title_block
		(title "03242023_DA0F0TMBIJ0_F0T_Motherboard_J_brd_V01_OCP.brd")
		(comment 1 "Grand Teton / footprint 1660 of 6105 (J24), pads 275-291 of 291")
	)
	(layers
		(0 "F.Cu" signal "TOP")
		(4 "In1.Cu" signal "GND")
		(6 "In2.Cu" signal "IN1")
		(8 "In3.Cu" signal "GND1")
		(10 "In4.Cu" signal "IN2")
		(12 "In5.Cu" signal "GND2")
		(14 "In6.Cu" signal "IN3")
		(16 "In7.Cu" signal "GND3")
		(18 "In8.Cu" signal "VCC")
		(20 "In9.Cu" signal "VCC1")
		(22 "In10.Cu" signal "GND4")
		(24 "In11.Cu" signal "IN4")
		(26 "In12.Cu" signal "GND5")
		(28 "In13.Cu" signal "IN5")
		(30 "In14.Cu" signal "GND6")
		(32 "In15.Cu" signal "IN6")
		(34 "In16.Cu" signal "GND7")
		(2 "B.Cu" signal "BOTTOM")
		(9 "F.Adhes" user "F.Adhesive")
		(11 "B.Adhes" user "B.Adhesive")
		(13 "F.Paste" user "Package Geometry/Pastemask Top")
		(15 "B.Paste" user "Package Geometry/Pastemask Bottom")
		(5 "F.SilkS" user "Ref Des/Silkscreen Top")
		(7 "B.SilkS" user "Ref Des/Silkscreen Bottom")
		(1 "F.Mask" user "Board Geometry/Soldermask Top")
		(3 "B.Mask" user "Board Geometry/Soldermask Bottom")
		(17 "Dwgs.User" user "User.Drawings")
		(19 "Cmts.User" user "User.Comments")
		(21 "Eco1.User" user "User.Eco1")
		(23 "Eco2.User" user "User.Eco2")
		(25 "Edge.Cuts" user "Board Geometry/Outline")
		(27 "Margin" user)
		(31 "F.CrtYd" user "Package Geometry/Place Bound Top")
		(29 "B.CrtYd" user "Package Geometry/Place Bound Bottom")
		(35 "F.Fab" user "Ref Des/Assembly Top")
		(33 "B.Fab" user "Ref Des/Assembly Bottom")
	)
	(footprint ""
		(layer "F.Cu")
		(at 17.73428 -258.091686)
		(property "Reference" "J24"
			(at -3.0607 -81.901792 0)
			(unlocked yes)
			(layer "F.SilkS")
			(effects
				(font
					(size 0.7874 0.5842)
					(thickness 0.1524)
				)
				(justify left)
			)
		)
		(property "Value" ""
			(at 0 0 0)
			(layer "F.Fab")
			(effects
				(font
					(size 1.27 1.27)
				)
			)
		)
		(duplicate_pad_numbers_are_jumpers no)
		(pad "275" smd rect
			(at 2.050034 52.274978 270)
			(size 0.519938 1.4986)
			(layers "F.Cu" "F.Mask" "F.Paste")
			(net "GND")
		)
		(pad "276" smd rect
			(at 2.050034 53.125116 270)
			(size 0.519938 1.4986)
			(layers "F.Cu" "F.Mask" "F.Paste")
			(net "M_D_CPU1_SB_DQ<23>")
		)
		(pad "277" smd rect
			(at 2.050034 53.975 270)
			(size 0.519938 1.4986)
			(layers "F.Cu" "F.Mask" "F.Paste")
			(net "GND")
		)
		(pad "278" smd rect
			(at 2.050034 54.824884 270)
			(size 0.519938 1.4986)
			(layers "F.Cu" "F.Mask" "F.Paste")
			(net "M_D_CPU1_SB_DQ<26>")
		)
		(pad "279" smd rect
			(at 2.050034 55.675022 270)
			(size 0.519938 1.4986)
			(layers "F.Cu" "F.Mask" "F.Paste")
			(net "GND")
		)
		(pad "280" smd rect
			(at 2.050034 56.524906 270)
			(size 0.519938 1.4986)
			(layers "F.Cu" "F.Mask" "F.Paste")
			(net "M_D_CPU1_SB_DQ<27>")
		)
		(pad "281" smd rect
			(at 2.050034 57.375044 270)
			(size 0.519938 1.4986)
			(layers "F.Cu" "F.Mask" "F.Paste")
			(net "GND")
		)
		(pad "282" smd rect
			(at 2.050034 58.224928 270)
			(size 0.519938 1.4986)
			(layers "F.Cu" "F.Mask" "F.Paste")
			(net "M_D_CPU1_SB_DQS_DN<8>")
		)
		(pad "283" smd rect
			(at 2.050034 59.075066 270)
			(size 0.519938 1.4986)
			(layers "F.Cu" "F.Mask" "F.Paste")
			(net "M_D_CPU1_SB_DQS_DP<8>")
		)
		(pad "284" smd rect
			(at 2.050034 59.92495 270)
			(size 0.519938 1.4986)
			(layers "F.Cu" "F.Mask" "F.Paste")
			(net "GND")
		)
		(pad "285" smd rect
			(at 2.050034 60.775088 270)
			(size 0.519938 1.4986)
			(layers "F.Cu" "F.Mask" "F.Paste")
			(net "M_D_CPU1_SB_DQ<30>")
		)
		(pad "286" smd rect
			(at 2.050034 61.624972 270)
			(size 0.519938 1.4986)
			(layers "F.Cu" "F.Mask" "F.Paste")
			(net "GND")
		)
		(pad "287" smd rect
			(at 2.050034 62.47511 270)
			(size 0.519938 1.4986)
			(layers "F.Cu" "F.Mask" "F.Paste")
			(net "M_D_CPU1_SB_DQ<31>")
		)
		(pad "288" smd rect
			(at 2.050034 63.324994 270)
			(size 0.519938 1.4986)
			(layers "F.Cu" "F.Mask" "F.Paste")
			(net "GND")
		)
		(pad "G1" thru_hole oval
			(at 0 -68.97497)
			(size 2.8194 1.5748)
			(drill oval 2.4384 1.1938)
			(layers "*.Cu" "*.Mask")
			(remove_unused_layers no)
			(net "GND")
			(clearance 0.127)
			(thermal_gap 0.127)
		)
		(pad "G2" thru_hole oval
			(at 0 3.875024)
			(size 2.8194 1.5748)
			(drill oval 2.4384 1.1938)
			(layers "*.Cu" "*.Mask")
			(remove_unused_layers no)
			(net "GND")
			(clearance 0.127)
			(thermal_gap 0.127)
		)
		(pad "G3" thru_hole oval
			(at 0 68.97497)
			(size 2.8194 1.5748)
			(drill oval 2.4384 1.1938)
			(layers "*.Cu" "*.Mask")
			(remove_unused_layers no)
			(net "GND")
			(clearance 0.127)
			(thermal_gap 0.127)
		)
	)
)
